(kicad_pcb
	(version 20260206)
	(generator "pcbnew")
	(generator_version "10.0")
	(general
		(thickness 1.6)
		(legacy_teardrops no)
	)
	(paper "A4")
	(title_block
		(title "Bryce Canyon_IOM_M2_16342-2_OCP.brd")
		(comment 1 "Bryce Canyon / footprints 213-220 of 1146")
	)
	(layers
		(0 "F.Cu" signal "TOP")
		(4 "In1.Cu" signal "L2GND")
		(6 "In2.Cu" signal "L3")
		(8 "In3.Cu" signal "L4VCC")
		(10 "In4.Cu" signal "L5VCC")
		(12 "In5.Cu" signal "L6")
		(14 "In6.Cu" signal "L7GND")
		(2 "B.Cu" signal "BOTTOM")
		(9 "F.Adhes" user "F.Adhesive")
		(11 "B.Adhes" user "B.Adhesive")
		(13 "F.Paste" user "Package Geometry/Pastemask Top")
		(15 "B.Paste" user "Package Geometry/Pastemask Bottom")
		(5 "F.SilkS" user "Ref Des/Silkscreen Top")
		(7 "B.SilkS" user "Ref Des/Silkscreen Bottom")
		(1 "F.Mask" user "Board Geometry/Soldermask Top")
		(3 "B.Mask" user "Board Geometry/Soldermask Bottom")
		(17 "Dwgs.User" user "User.Drawings")
		(19 "Cmts.User" user "User.Comments")
		(21 "Eco1.User" user "User.Eco1")
		(23 "Eco2.User" user "User.Eco2")
		(25 "Edge.Cuts" user "Board Geometry/Outline")
		(27 "Margin" user)
		(31 "F.CrtYd" user "Package Geometry/Place Bound Top")
		(29 "B.CrtYd" user "Package Geometry/Place Bound Bottom")
		(35 "F.Fab" user "Ref Des/Assembly Top")
		(33 "B.Fab" user "Ref Des/Assembly Bottom")
	)
	(footprint ""
		(layer "F.Cu")
		(at 37.589968 -132.000244 90)
		(property "Reference" "R379"
			(at 0 0 90)
			(layer "F.SilkS")
			(hide yes)
			(effects
				(font
					(size 1.27 1.27)
				)
			)
		)
		(property "Value" "4K7R2F-GP"
			(at 0.064008 -3.993896 90)
			(unlocked yes)
			(layer "F.Fab")
			(hide yes)
			(effects
				(font
					(size 1.016 1.016)
					(thickness 0.1524)
				)
			)
		)
		(property "Device Type" "R402H16"
			(at 0.064008 -5.517896 90)
			(unlocked yes)
			(layer "F.Fab")
			(hide yes)
			(effects
				(font
					(size 1.016 1.016)
					(thickness 0.1524)
				)
			)
		)
		(duplicate_pad_numbers_are_jumpers no)
		(fp_line
			(start 0.508 -0.9398)
			(end -0.508 -0.9398)
			(stroke
				(width 0.1524)
				(type default)
			)
			(layer "F.SilkS")
		)
		(fp_line
			(start -0.508 -0.9398)
			(end -0.508 0.9398)
			(stroke
				(width 0.1524)
				(type default)
			)
			(layer "F.SilkS")
		)
		(fp_rect
			(start -0.508 0.9398)
			(end 0.508 -0.9398)
			(stroke
				(width 0)
				(type default)
			)
			(fill no)
			(layer "F.CrtYd")
		)
		(fp_rect
			(start -0.508 0.9398)
			(end 0.508 -0.9398)
			(stroke
				(width 0)
				(type default)
			)
			(fill no)
			(layer "F.Fab")
		)
		(pad "1" smd custom
			(at 0 -0.4445 90)
			(size 0.1397 0.1397)
			(layers "F.Cu" "F.Mask" "F.Paste")
			(net "P3V3_STBY")
			(options
				(clearance outline)
				(anchor circle)
			)
			(primitives
				(gr_poly
					(pts
						(arc
							(start -0.1778 -0.2794)
							(mid -0.249642 -0.249642)
							(end -0.2794 -0.1778)
						)
						(arc
							(start -0.2794 0.1778)
							(mid -0.249642 0.249642)
							(end -0.1778 0.2794)
						)
						(arc
							(start 0.1778 0.2794)
							(mid 0.249642 0.249642)
							(end 0.2794 0.1778)
						)
						(arc
							(start 0.2794 -0.1778)
							(mid 0.249642 -0.249642)
							(end 0.1778 -0.2794)
						)
					)
					(width 0)
					(fill yes)
				)
			)
		)
		(pad "2" smd custom
			(at 0 0.4445 90)
			(size 0.1397 0.1397)
			(layers "F.Cu" "F.Mask" "F.Paste")
			(net "BMC_GPIOZ7")
			(options
				(clearance outline)
				(anchor circle)
			)
			(primitives
				(gr_poly
					(pts
						(arc
							(start -0.1778 -0.2794)
							(mid -0.249642 -0.249642)
							(end -0.2794 -0.1778)
						)
						(arc
							(start -0.2794 0.1778)
							(mid -0.249642 0.249642)
							(end -0.1778 0.2794)
						)
						(arc
							(start 0.1778 0.2794)
							(mid 0.249642 0.249642)
							(end 0.2794 0.1778)
						)
						(arc
							(start 0.2794 -0.1778)
							(mid 0.249642 -0.249642)
							(end 0.1778 -0.2794)
						)
					)
					(width 0)
					(fill yes)
				)
			)
		)
	)
	(footprint ""
		(layer "F.Cu")
		(at 207.8736 -108.1532 90)
		(property "Reference" "R550"
			(at 0 0 90)
			(layer "F.SilkS")
			(hide yes)
			(effects
				(font
					(size 1.27 1.27)
				)
			)
		)
		(property "Value" "4K7R2F-GP"
			(at 0.064008 -3.993896 90)
			(unlocked yes)
			(layer "F.Fab")
			(hide yes)
			(effects
				(font
					(size 1.016 1.016)
					(thickness 0.1524)
				)
			)
		)
		(property "Device Type" "R402H16"
			(at 0.064008 -5.517896 90)
			(unlocked yes)
			(layer "F.Fab")
			(hide yes)
			(effects
				(font
					(size 1.016 1.016)
					(thickness 0.1524)
				)
			)
		)
		(duplicate_pad_numbers_are_jumpers no)
		(fp_line
			(start 0.508 -0.9398)
			(end -0.508 -0.9398)
			(stroke
				(width 0.1524)
				(type default)
			)
			(layer "F.SilkS")
		)
		(fp_line
			(start -0.508 -0.9398)
			(end -0.508 0.9398)
			(stroke
				(width 0.1524)
				(type default)
			)
			(layer "F.SilkS")
		)
		(fp_rect
			(start -0.508 0.9398)
			(end 0.508 -0.9398)
			(stroke
				(width 0)
				(type default)
			)
			(fill no)
			(layer "F.CrtYd")
		)
		(fp_rect
			(start -0.508 0.9398)
			(end 0.508 -0.9398)
			(stroke
				(width 0)
				(type default)
			)
			(fill no)
			(layer "F.Fab")
		)
		(pad "1" smd custom
			(at 0 -0.4445 90)
			(size 0.1397 0.1397)
			(layers "F.Cu" "F.Mask" "F.Paste")
			(net "TEMP_2_A2")
			(options
				(clearance outline)
				(anchor circle)
			)
			(primitives
				(gr_poly
					(pts
						(arc
							(start -0.1778 -0.2794)
							(mid -0.249642 -0.249642)
							(end -0.2794 -0.1778)
						)
						(arc
							(start -0.2794 0.1778)
							(mid -0.249642 0.249642)
							(end -0.1778 0.2794)
						)
						(arc
							(start 0.1778 0.2794)
							(mid 0.249642 0.249642)
							(end 0.2794 0.1778)
						)
						(arc
							(start 0.2794 -0.1778)
							(mid 0.249642 -0.249642)
							(end 0.1778 -0.2794)
						)
					)
					(width 0)
					(fill yes)
				)
			)
		)
		(pad "2" smd custom
			(at 0 0.4445 90)
			(size 0.1397 0.1397)
			(layers "F.Cu" "F.Mask" "F.Paste")
			(net "GND")
			(options
				(clearance outline)
				(anchor circle)
			)
			(primitives
				(gr_poly
					(pts
						(arc
							(start -0.1778 -0.2794)
							(mid -0.249642 -0.249642)
							(end -0.2794 -0.1778)
						)
						(arc
							(start -0.2794 0.1778)
							(mid -0.249642 0.249642)
							(end -0.1778 0.2794)
						)
						(arc
							(start 0.1778 0.2794)
							(mid 0.249642 0.249642)
							(end 0.2794 0.1778)
						)
						(arc
							(start 0.2794 -0.1778)
							(mid 0.249642 -0.249642)
							(end 0.1778 -0.2794)
						)
					)
					(width 0)
					(fill yes)
				)
			)
		)
	)
	(footprint ""
		(layer "F.Cu")
		(at 160.472374 -15.293594)
		(property "Reference" "C207"
			(at 0 0 0)
			(layer "F.SilkS")
			(hide yes)
			(effects
				(font
					(size 1.27 1.27)
				)
			)
		)
		(property "Value" "SCD1U50V3KX-GP"
			(at 0 -2.8194 0)
			(unlocked yes)
			(layer "F.Fab")
			(hide yes)
			(effects
				(font
					(size 1.016 1.016)
					(thickness 0.1524)
				)
			)
		)
		(property "Device Type" "C603H36"
			(at 0 -4.3434 0)
			(unlocked yes)
			(layer "F.Fab")
			(hide yes)
			(effects
				(font
					(size 1.016 1.016)
					(thickness 0.1524)
				)
			)
		)
		(duplicate_pad_numbers_are_jumpers no)
		(fp_line
			(start 0.508 0)
			(end -0.508 0)
			(stroke
				(width 0.2032)
				(type default)
			)
			(layer "F.SilkS")
		)
		(fp_rect
			(start -0.5842 1.3335)
			(end 0.5842 -1.3335)
			(stroke
				(width 0)
				(type default)
			)
			(fill no)
			(layer "F.CrtYd")
		)
		(fp_rect
			(start -0.5842 1.3335)
			(end 0.5842 -1.3335)
			(stroke
				(width 0)
				(type default)
			)
			(fill no)
			(layer "F.Fab")
		)
		(pad "1" smd custom
			(at 0 -0.762)
			(size 0.2159 0.2159)
			(layers "F.Cu" "F.Mask" "F.Paste")
			(net "P1V8_STBY_VBST_RR")
			(options
				(clearance outline)
				(anchor circle)
			)
			(primitives
				(gr_poly
					(pts
						(arc
							(start -0.3302 -0.4318)
							(mid -0.402042 -0.402042)
							(end -0.4318 -0.3302)
						)
						(arc
							(start -0.4318 0.3302)
							(mid -0.402042 0.402042)
							(end -0.3302 0.4318)
						)
						(arc
							(start 0.3302 0.4318)
							(mid 0.402042 0.402042)
							(end 0.4318 0.3302)
						)
						(arc
							(start 0.4318 -0.3302)
							(mid 0.402042 -0.402042)
							(end 0.3302 -0.4318)
						)
					)
					(width 0)
					(fill yes)
				)
			)
		)
		(pad "2" smd custom
			(at 0 0.762)
			(size 0.2159 0.2159)
			(layers "F.Cu" "F.Mask" "F.Paste")
			(net "P1V8_STBY_SW")
			(options
				(clearance outline)
				(anchor circle)
			)
			(primitives
				(gr_poly
					(pts
						(arc
							(start -0.3302 -0.4318)
							(mid -0.402042 -0.402042)
							(end -0.4318 -0.3302)
						)
						(arc
							(start -0.4318 0.3302)
							(mid -0.402042 0.402042)
							(end -0.3302 0.4318)
						)
						(arc
							(start 0.3302 0.4318)
							(mid 0.402042 0.402042)
							(end 0.4318 0.3302)
						)
						(arc
							(start 0.4318 -0.3302)
							(mid 0.402042 -0.402042)
							(end 0.3302 -0.4318)
						)
					)
					(width 0)
					(fill yes)
				)
			)
		)
	)
	(footprint ""
		(layer "F.Cu")
		(at 54.713124 -162.481768 180)
		(property "Reference" "C118"
			(at 0 0 180)
			(layer "F.SilkS")
			(hide yes)
			(effects
				(font
					(size 1.27 1.27)
				)
			)
		)
		(property "Value" "SCD1U25V2KX-2-GP"
			(at 1.1811 -2.7051 180)
			(unlocked yes)
			(layer "F.Fab")
			(hide yes)
			(effects
				(font
					(size 1.016 1.016)
					(thickness 0.1524)
				)
			)
		)
		(property "Device Type" "C402H22"
			(at 1.1811 -4.2291 180)
			(unlocked yes)
			(layer "F.Fab")
			(hide yes)
			(effects
				(font
					(size 1.016 1.016)
					(thickness 0.1524)
				)
			)
		)
		(duplicate_pad_numbers_are_jumpers no)
		(fp_rect
			(start -0.4318 0.9525)
			(end 0.4318 -0.9525)
			(stroke
				(width 0)
				(type default)
			)
			(fill no)
			(layer "F.CrtYd")
		)
		(fp_rect
			(start -0.4318 0.9525)
			(end 0.4318 -0.9525)
			(stroke
				(width 0)
				(type default)
			)
			(fill no)
			(layer "F.Fab")
		)
		(pad "1" smd custom
			(at 0 -0.4445 180)
			(size 0.1524 0.1524)
			(layers "F.Cu" "F.Mask" "F.Paste")
			(net "ADC_P1V8_STBY")
			(options
				(clearance outline)
				(anchor circle)
			)
			(primitives
				(gr_poly
					(pts
						(arc
							(start 0.3048 -0.2032)
							(mid 0.275042 -0.275042)
							(end 0.2032 -0.3048)
						)
						(arc
							(start -0.2032 -0.3048)
							(mid -0.275042 -0.275042)
							(end -0.3048 -0.2032)
						)
						(arc
							(start -0.3048 0.2032)
							(mid -0.275042 0.275042)
							(end -0.2032 0.3048)
						)
						(arc
							(start 0.2032 0.3048)
							(mid 0.275042 0.275042)
							(end 0.3048 0.2032)
						)
					)
					(width 0)
					(fill yes)
				)
			)
		)
		(pad "2" smd custom
			(at 0 0.4445 180)
			(size 0.1524 0.1524)
			(layers "F.Cu" "F.Mask" "F.Paste")
			(net "GND")
			(options
				(clearance outline)
				(anchor circle)
			)
			(primitives
				(gr_poly
					(pts
						(arc
							(start 0.3048 -0.2032)
							(mid 0.275042 -0.275042)
							(end 0.2032 -0.3048)
						)
						(arc
							(start -0.2032 -0.3048)
							(mid -0.275042 -0.275042)
							(end -0.3048 -0.2032)
						)
						(arc
							(start -0.3048 0.2032)
							(mid -0.275042 0.275042)
							(end -0.2032 0.3048)
						)
						(arc
							(start 0.2032 0.3048)
							(mid 0.275042 0.275042)
							(end 0.3048 0.2032)
						)
					)
					(width 0)
					(fill yes)
				)
			)
		)
	)
	(footprint ""
		(layer "F.Cu")
		(at 87.6554 -136.6266 180)
		(property "Reference" "R133"
			(at 0 0 180)
			(layer "F.SilkS")
			(hide yes)
			(effects
				(font
					(size 1.27 1.27)
				)
			)
		)
		(property "Value" "8K2R2J-3-GP"
			(at 0.064008 -3.993896 180)
			(unlocked yes)
			(layer "F.Fab")
			(hide yes)
			(effects
				(font
					(size 1.016 1.016)
					(thickness 0.1524)
				)
			)
		)
		(property "Device Type" "R402H16"
			(at 0.064008 -5.517896 180)
			(unlocked yes)
			(layer "F.Fab")
			(hide yes)
			(effects
				(font
					(size 1.016 1.016)
					(thickness 0.1524)
				)
			)
		)
		(duplicate_pad_numbers_are_jumpers no)
		(fp_line
			(start 0.508 -0.9398)
			(end -0.508 -0.9398)
			(stroke
				(width 0.1524)
				(type default)
			)
			(layer "F.SilkS")
		)
		(fp_line
			(start -0.508 -0.9398)
			(end -0.508 0.9398)
			(stroke
				(width 0.1524)
				(type default)
			)
			(layer "F.SilkS")
		)
		(fp_rect
			(start -0.508 0.9398)
			(end 0.508 -0.9398)
			(stroke
				(width 0)
				(type default)
			)
			(fill no)
			(layer "F.CrtYd")
		)
		(fp_rect
			(start -0.508 0.9398)
			(end 0.508 -0.9398)
			(stroke
				(width 0)
				(type default)
			)
			(fill no)
			(layer "F.Fab")
		)
		(pad "1" smd custom
			(at 0 -0.4445 180)
			(size 0.1397 0.1397)
			(layers "F.Cu" "F.Mask" "F.Paste")
			(net "P3V3_STBY")
			(options
				(clearance outline)
				(anchor circle)
			)
			(primitives
				(gr_poly
					(pts
						(arc
							(start -0.1778 -0.2794)
							(mid -0.249642 -0.249642)
							(end -0.2794 -0.1778)
						)
						(arc
							(start -0.2794 0.1778)
							(mid -0.249642 0.249642)
							(end -0.1778 0.2794)
						)
						(arc
							(start 0.1778 0.2794)
							(mid 0.249642 0.249642)
							(end 0.2794 0.1778)
						)
						(arc
							(start 0.2794 -0.1778)
							(mid 0.249642 -0.249642)
							(end 0.1778 -0.2794)
						)
					)
					(width 0)
					(fill yes)
				)
			)
		)
		(pad "2" smd custom
			(at 0 0.4445 180)
			(size 0.1397 0.1397)
			(layers "F.Cu" "F.Mask" "F.Paste")
			(net "EEPROM_A0")
			(options
				(clearance outline)
				(anchor circle)
			)
			(primitives
				(gr_poly
					(pts
						(arc
							(start -0.1778 -0.2794)
							(mid -0.249642 -0.249642)
							(end -0.2794 -0.1778)
						)
						(arc
							(start -0.2794 0.1778)
							(mid -0.249642 0.249642)
							(end -0.1778 0.2794)
						)
						(arc
							(start 0.1778 0.2794)
							(mid 0.249642 0.249642)
							(end 0.2794 0.1778)
						)
						(arc
							(start 0.2794 -0.1778)
							(mid 0.249642 -0.249642)
							(end 0.1778 -0.2794)
						)
					)
					(width 0)
					(fill yes)
				)
			)
		)
	)
	(footprint ""
		(layer "F.Cu")
		(at 82.94116 -157.3276 90)
		(property "Reference" "C238"
			(at 0 0 90)
			(layer "F.SilkS")
			(hide yes)
			(effects
				(font
					(size 1.27 1.27)
				)
			)
		)
		(property "Value" "SC10U6D3V5KX-4GP"
			(at -0.0762 -6.1214 90)
			(unlocked yes)
			(layer "F.Fab")
			(hide yes)
			(effects
				(font
					(size 1.016 1.016)
					(thickness 0.1524)
				)
			)
		)
		(property "Device Type" "C805H58"
			(at -0.0762 -8.1534 90)
			(unlocked yes)
			(layer "F.Fab")
			(hide yes)
			(effects
				(font
					(size 1.016 1.016)
					(thickness 0.1524)
				)
			)
		)
		(duplicate_pad_numbers_are_jumpers no)
		(fp_line
			(start 0.635 0)
			(end -0.635 0)
			(stroke
				(width 0.508)
				(type default)
			)
			(layer "F.SilkS")
		)
		(fp_rect
			(start -0.9652 1.778)
			(end 0.9652 -1.778)
			(stroke
				(width 0)
				(type default)
			)
			(fill no)
			(layer "F.CrtYd")
		)
		(fp_poly
			(pts
				(xy -0.9652 -1.778) (xy 0.9652 -1.778) (xy 0.9652 1.778) (xy -0.9652 1.778)
			)
			(stroke
				(width 0)
				(type default)
			)
			(fill no)
			(layer "F.Fab")
		)
		(pad "1" smd rect
			(at 0 -0.9652 90)
			(size 1.397 1.143)
			(layers "F.Cu" "F.Mask" "F.Paste")
			(net "TPS74801_P1V15_STBY_OUT")
		)
		(pad "2" smd rect
			(at 0 0.9652 90)
			(size 1.397 1.143)
			(layers "F.Cu" "F.Mask" "F.Paste")
			(net "GND")
		)
	)
	(footprint ""
		(layer "F.Cu")
		(at 52.8066 -162.4838 180)
		(property "Reference" "C122"
			(at 0 0 180)
			(layer "F.SilkS")
			(hide yes)
			(effects
				(font
					(size 1.27 1.27)
				)
			)
		)
		(property "Value" "SCD1U25V2KX-2-GP"
			(at 1.1811 -2.7051 180)
			(unlocked yes)
			(layer "F.Fab")
			(hide yes)
			(effects
				(font
					(size 1.016 1.016)
					(thickness 0.1524)
				)
			)
		)
		(property "Device Type" "C402H22"
			(at 1.1811 -4.2291 180)
			(unlocked yes)
			(layer "F.Fab")
			(hide yes)
			(effects
				(font
					(size 1.016 1.016)
					(thickness 0.1524)
				)
			)
		)
		(duplicate_pad_numbers_are_jumpers no)
		(fp_rect
			(start -0.4318 0.9525)
			(end 0.4318 -0.9525)
			(stroke
				(width 0)
				(type default)
			)
			(fill no)
			(layer "F.CrtYd")
		)
		(fp_rect
			(start -0.4318 0.9525)
			(end 0.4318 -0.9525)
			(stroke
				(width 0)
				(type default)
			)
			(fill no)
			(layer "F.Fab")
		)
		(pad "1" smd custom
			(at 0 -0.4445 180)
			(size 0.1524 0.1524)
			(layers "F.Cu" "F.Mask" "F.Paste")
			(net "ADC_P3V3")
			(options
				(clearance outline)
				(anchor circle)
			)
			(primitives
				(gr_poly
					(pts
						(arc
							(start 0.3048 -0.2032)
							(mid 0.275042 -0.275042)
							(end 0.2032 -0.3048)
						)
						(arc
							(start -0.2032 -0.3048)
							(mid -0.275042 -0.275042)
							(end -0.3048 -0.2032)
						)
						(arc
							(start -0.3048 0.2032)
							(mid -0.275042 0.275042)
							(end -0.2032 0.3048)
						)
						(arc
							(start 0.2032 0.3048)
							(mid 0.275042 0.275042)
							(end 0.3048 0.2032)
						)
					)
					(width 0)
					(fill yes)
				)
			)
		)
		(pad "2" smd custom
			(at 0 0.4445 180)
			(size 0.1524 0.1524)
			(layers "F.Cu" "F.Mask" "F.Paste")
			(net "GND")
			(options
				(clearance outline)
				(anchor circle)
			)
			(primitives
				(gr_poly
					(pts
						(arc
							(start 0.3048 -0.2032)
							(mid 0.275042 -0.275042)
							(end 0.2032 -0.3048)
						)
						(arc
							(start -0.2032 -0.3048)
							(mid -0.275042 -0.275042)
							(end -0.3048 -0.2032)
						)
						(arc
							(start -0.3048 0.2032)
							(mid -0.275042 0.275042)
							(end -0.2032 0.3048)
						)
						(arc
							(start 0.2032 0.3048)
							(mid 0.275042 0.275042)
							(end 0.3048 0.2032)
						)
					)
					(width 0)
					(fill yes)
				)
			)
		)
	)
	(footprint ""
		(layer "F.Cu")
		(at 37.299646 -173.66361 90)
		(property "Reference" "R496"
			(at 0 0 90)
			(layer "F.SilkS")
			(hide yes)
			(effects
				(font
					(size 1.27 1.27)
				)
			)
		)
		(property "Value" "44K2R2F-1-GP"
			(at 0.064008 -3.993896 90)
			(unlocked yes)
			(layer "F.Fab")
			(hide yes)
			(effects
				(font
					(size 1.016 1.016)
					(thickness 0.1524)
				)
			)
		)
		(property "Device Type" "R402H16"
			(at 0.064008 -5.517896 90)
			(unlocked yes)
			(layer "F.Fab")
			(hide yes)
			(effects
				(font
					(size 1.016 1.016)
					(thickness 0.1524)
				)
			)
		)
		(duplicate_pad_numbers_are_jumpers no)
		(fp_line
			(start 0.508 -0.9398)
			(end -0.508 -0.9398)
			(stroke
				(width 0.1524)
				(type default)
			)
			(layer "F.SilkS")
		)
		(fp_line
			(start -0.508 -0.9398)
			(end -0.508 0.9398)
			(stroke
				(width 0.1524)
				(type default)
			)
			(layer "F.SilkS")
		)
		(fp_rect
			(start -0.508 0.9398)
			(end 0.508 -0.9398)
			(stroke
				(width 0)
				(type default)
			)
			(fill no)
			(layer "F.CrtYd")
		)
		(fp_rect
			(start -0.508 0.9398)
			(end 0.508 -0.9398)
			(stroke
				(width 0)
				(type default)
			)
			(fill no)
			(layer "F.Fab")
		)
		(pad "1" smd custom
			(at 0 -0.4445 90)
			(size 0.1397 0.1397)
			(layers "F.Cu" "F.Mask" "F.Paste")
			(net "P3V3_STBY_VFB")
			(options
				(clearance outline)
				(anchor circle)
			)
			(primitives
				(gr_poly
					(pts
						(arc
							(start -0.1778 -0.2794)
							(mid -0.249642 -0.249642)
							(end -0.2794 -0.1778)
						)
						(arc
							(start -0.2794 0.1778)
							(mid -0.249642 0.249642)
							(end -0.1778 0.2794)
						)
						(arc
							(start 0.1778 0.2794)
							(mid 0.249642 0.249642)
							(end 0.2794 0.1778)
						)
						(arc
							(start 0.2794 -0.1778)
							(mid 0.249642 -0.249642)
							(end 0.1778 -0.2794)
						)
					)
					(width 0)
					(fill yes)
				)
			)
		)
		(pad "2" smd custom
			(at 0 0.4445 90)
			(size 0.1397 0.1397)
			(layers "F.Cu" "F.Mask" "F.Paste")
			(net "P3V3_STBY_VFB_R")
			(options
				(clearance outline)
				(anchor circle)
			)
			(primitives
				(gr_poly
					(pts
						(arc
							(start -0.1778 -0.2794)
							(mid -0.249642 -0.249642)
							(end -0.2794 -0.1778)
						)
						(arc
							(start -0.2794 0.1778)
							(mid -0.249642 0.249642)
							(end -0.1778 0.2794)
						)
						(arc
							(start 0.1778 0.2794)
							(mid 0.249642 0.249642)
							(end 0.2794 0.1778)
						)
						(arc
							(start 0.2794 -0.1778)
							(mid 0.249642 -0.249642)
							(end 0.1778 -0.2794)
						)
					)
					(width 0)
					(fill yes)
				)
			)
		)
	)
)
